# T6G (Grand Teton) — schematic netlist excerpt (pin names and nets, part order shuffled) for the footprints in the layout excerpt that follows; sources: Cadence DE-HDL packaged netlist, KiCad conversion of 04192023_DAF0TMB3IC0_F0TG_MB_C_brd_V02_OCP.brd

PC2088  Q_CAP  0.01UF 50V 10% EMPTY  pkg C0402  page 134 : A = P12V_OCP_SFF ; B = P12V_OCP_GATE_1
R6108  Q_RES  0 5% CHIP  pkg 0402LF  page 172 : A = HDT_HDR_TDO ; B = HDT_HDR_TDO_R

(kicad_pcb
	(version 20260206)
	(generator "pcbnew")
	(generator_version "10.0")
	(general
		(thickness 1.6)
		(legacy_teardrops no)
	)
	(paper "A4")
	(title_block
		(title "04192023_DAF0TMB3IC0_F0TG_MB_C_brd_V02_OCP.brd")
		(comment 1 "Grand Teton / footprints 4372-4373 of 8354")
	)
	(layers
		(0 "F.Cu" signal "TOP")
		(4 "In1.Cu" signal "GND")
		(6 "In2.Cu" signal "IN1")
		(8 "In3.Cu" signal "GND1")
		(10 "In4.Cu" signal "IN2")
		(12 "In5.Cu" signal "GND2")
		(14 "In6.Cu" signal "IN3")
		(16 "In7.Cu" signal "GND3")
		(18 "In8.Cu" signal "VCC")
		(20 "In9.Cu" signal "VCC1")
		(22 "In10.Cu" signal "GND4")
		(24 "In11.Cu" signal "IN4")
		(26 "In12.Cu" signal "GND5")
		(28 "In13.Cu" signal "IN5")
		(30 "In14.Cu" signal "GND6")
		(32 "In15.Cu" signal "IN6")
		(34 "In16.Cu" signal "GND7")
		(2 "B.Cu" signal "BOTTOM")
		(9 "F.Adhes" user "F.Adhesive")
		(11 "B.Adhes" user "B.Adhesive")
		(13 "F.Paste" user "Package Geometry/Pastemask Top")
		(15 "B.Paste" user "Package Geometry/Pastemask Bottom")
		(5 "F.SilkS" user "Ref Des/Silkscreen Top")
		(7 "B.SilkS" user "Ref Des/Silkscreen Bottom")
		(1 "F.Mask" user "Board Geometry/Soldermask Top")
		(3 "B.Mask" user "Board Geometry/Soldermask Bottom")
		(17 "Dwgs.User" user "User.Drawings")
		(19 "Cmts.User" user "User.Comments")
		(21 "Eco1.User" user "User.Eco1")
		(23 "Eco2.User" user "User.Eco2")
		(25 "Edge.Cuts" user "Board Geometry/Outline")
		(27 "Margin" user)
		(31 "F.CrtYd" user "Package Geometry/Place Bound Top")
		(29 "B.CrtYd" user "Package Geometry/Place Bound Bottom")
		(35 "F.Fab" user "Ref Des/Assembly Top")
		(33 "B.Fab" user "Ref Des/Assembly Bottom")
	)
	(footprint ""
		(layer "F.Cu")
		(at 453.054212 -24.619458 180)
		(property "Reference" "PC2088"
			(at 0 0 180)
			(layer "F.SilkS")
			(hide yes)
			(effects
				(font
					(size 1.27 1.27)
				)
			)
		)
		(property "Value" ""
			(at 0 0 180)
			(layer "F.Fab")
			(effects
				(font
					(size 1.27 1.27)
				)
			)
		)
		(duplicate_pad_numbers_are_jumpers no)
		(fp_line
			(start 0.7874 0.4064)
			(end -0.7874 0.4064)
			(stroke
				(width 0.1524)
				(type default)
			)
			(layer "F.SilkS")
		)
		(fp_line
			(start 0.7874 -0.4064)
			(end 0.7874 0.4064)
			(stroke
				(width 0.1524)
				(type default)
			)
			(layer "F.SilkS")
		)
		(fp_line
			(start -0.7874 0.4064)
			(end -0.7874 -0.4064)
			(stroke
				(width 0.1524)
				(type default)
			)
			(layer "F.SilkS")
		)
		(fp_line
			(start -0.7874 -0.4064)
			(end 0.7874 -0.4064)
			(stroke
				(width 0.1524)
				(type default)
			)
			(layer "F.SilkS")
		)
		(fp_line
			(start 0.67945 0.3048)
			(end 0.120396 0.3048)
			(stroke
				(width 0.1)
				(type default)
			)
			(layer "F.Fab")
		)
		(fp_line
			(start 0.67945 -0.3048)
			(end 0.67945 0.3048)
			(stroke
				(width 0.1)
				(type default)
			)
			(layer "F.Fab")
		)
		(fp_line
			(start 0.12065 -0.2794)
			(end 0.12065 -0.3048)
			(stroke
				(width 0.1)
				(type default)
			)
			(layer "F.Fab")
		)
		(fp_line
			(start 0.12065 -0.3048)
			(end 0.67945 -0.3048)
			(stroke
				(width 0.1)
				(type default)
			)
			(layer "F.Fab")
		)
		(fp_line
			(start 0.120396 0.3048)
			(end 0.120396 0.2794)
			(stroke
				(width 0.1)
				(type default)
			)
			(layer "F.Fab")
		)
		(fp_line
			(start 0.120396 0.2794)
			(end -0.12065 0.2794)
			(stroke
				(width 0.1)
				(type default)
			)
			(layer "F.Fab")
		)
		(fp_line
			(start -0.12065 0.3048)
			(end -0.67945 0.3048)
			(stroke
				(width 0.1)
				(type default)
			)
			(layer "F.Fab")
		)
		(fp_line
			(start -0.12065 0.2794)
			(end -0.12065 0.3048)
			(stroke
				(width 0.1)
				(type default)
			)
			(layer "F.Fab")
		)
		(fp_line
			(start -0.12065 -0.2794)
			(end 0.12065 -0.2794)
			(stroke
				(width 0.1)
				(type default)
			)
			(layer "F.Fab")
		)
		(fp_line
			(start -0.12065 -0.305054)
			(end -0.12065 -0.2794)
			(stroke
				(width 0.1)
				(type default)
			)
			(layer "F.Fab")
		)
		(fp_line
			(start -0.67945 0.3048)
			(end -0.67945 -0.305054)
			(stroke
				(width 0.1)
				(type default)
			)
			(layer "F.Fab")
		)
		(fp_line
			(start -0.67945 -0.305054)
			(end -0.12065 -0.305054)
			(stroke
				(width 0.1)
				(type default)
			)
			(layer "F.Fab")
		)
		(pad "1" smd circle
			(at -0.40005 0 180)
			(size 0 0)
			(layers "F.Cu" "F.Mask" "F.Paste")
			(net "P12V_OCP_SFF")
		)
		(pad "2" smd circle
			(at 0.40005 0 180)
			(size 0 0)
			(layers "F.Cu" "F.Mask" "F.Paste")
			(net "P12V_OCP_GATE_1")
		)
	)
	(footprint ""
		(layer "F.Cu")
		(at 120.76049 -52.86629 90)
		(property "Reference" "R6108"
			(at 0 0 90)
			(layer "F.SilkS")
			(hide yes)
			(effects
				(font
					(size 1.27 1.27)
				)
			)
		)
		(property "Value" ""
			(at 0 0 90)
			(layer "F.Fab")
			(effects
				(font
					(size 1.27 1.27)
				)
			)
		)
		(duplicate_pad_numbers_are_jumpers no)
		(fp_line
			(start 0.7874 -0.4064)
			(end 0.7874 0.4064)
			(stroke
				(width 0.1524)
				(type default)
			)
			(layer "F.SilkS")
		)
		(fp_line
			(start -0.7874 -0.4064)
			(end 0.7874 -0.4064)
			(stroke
				(width 0.1524)
				(type default)
			)
			(layer "F.SilkS")
		)
		(fp_line
			(start 0.7874 0.4064)
			(end -0.7874 0.4064)
			(stroke
				(width 0.1524)
				(type default)
			)
			(layer "F.SilkS")
		)
		(fp_line
			(start -0.7874 0.4064)
			(end -0.7874 -0.4064)
			(stroke
				(width 0.1524)
				(type default)
			)
			(layer "F.SilkS")
		)
		(fp_line
			(start -0.12065 -0.305054)
			(end -0.12065 -0.2794)
			(stroke
				(width 0.1)
				(type default)
			)
			(layer "F.Fab")
		)
		(fp_line
			(start -0.67945 -0.305054)
			(end -0.12065 -0.305054)
			(stroke
				(width 0.1)
				(type default)
			)
			(layer "F.Fab")
		)
		(fp_line
			(start 0.67945 -0.3048)
			(end 0.67945 0.3048)
			(stroke
				(width 0.1)
				(type default)
			)
			(layer "F.Fab")
		)
		(fp_line
			(start 0.12065 -0.3048)
			(end 0.67945 -0.3048)
			(stroke
				(width 0.1)
				(type default)
			)
			(layer "F.Fab")
		)
		(fp_line
			(start 0.12065 -0.2794)
			(end 0.12065 -0.3048)
			(stroke
				(width 0.1)
				(type default)
			)
			(layer "F.Fab")
		)
		(fp_line
			(start -0.12065 -0.2794)
			(end 0.12065 -0.2794)
			(stroke
				(width 0.1)
				(type default)
			)
			(layer "F.Fab")
		)
		(fp_line
			(start 0.120396 0.2794)
			(end -0.12065 0.2794)
			(stroke
				(width 0.1)
				(type default)
			)
			(layer "F.Fab")
		)
		(fp_line
			(start -0.12065 0.2794)
			(end -0.12065 0.3048)
			(stroke
				(width 0.1)
				(type default)
			)
			(layer "F.Fab")
		)
		(fp_line
			(start 0.67945 0.3048)
			(end 0.120396 0.3048)
			(stroke
				(width 0.1)
				(type default)
			)
			(layer "F.Fab")
		)
		(fp_line
			(start 0.120396 0.3048)
			(end 0.120396 0.2794)
			(stroke
				(width 0.1)
				(type default)
			)
			(layer "F.Fab")
		)
		(fp_line
			(start -0.12065 0.3048)
			(end -0.67945 0.3048)
			(stroke
				(width 0.1)
				(type default)
			)
			(layer "F.Fab")
		)
		(fp_line
			(start -0.67945 0.3048)
			(end -0.67945 -0.305054)
			(stroke
				(width 0.1)
				(type default)
			)
			(layer "F.Fab")
		)
		(pad "1" smd circle
			(at -0.40005 0 90)
			(size 0 0)
			(layers "F.Cu" "F.Mask" "F.Paste")
			(net "HDT_HDR_TDO")
		)
		(pad "2" smd circle
			(at 0.40005 0 90)
			(size 0 0)
			(layers "F.Cu" "F.Mask" "F.Paste")
			(net "HDT_HDR_TDO_R")
		)
	)
)
